# S9S_MB_2U (Grand Teton) — schematic netlist excerpt (pin names and nets, part order shuffled) for the footprints in the layout excerpt that follows; sources: Cadence DE-HDL packaged netlist, KiCad conversion of 03242023_DA0F0TMBIJ0_F0T_Motherboard_J_brd_V01_OCP.brd

PU6_P0_8  ISL99390FRZTR5935  ISL99390FRZ-TR5935 IC  pkg QFN21_6X5XB  page 270
  VOS  = PVCCIN_CPU0_VOS8
  AGND  = GND
  VCC  = PVCCIN_CPU0_VDD8
  PVCC  = PVCCIN_CPU0_PVCC
  PGND1  = GND
  GL1  = NC
  PGND2  = GND
  SW  = SW_PVCCIN_CPU0_SW8
  VIN1  = SW_P12V_PVCCIN_CPU0_FLT
  VIN2  = SW_P12V_PVCCIN_CPU0_FLT
  DNC  = NC
  PHASE  = SW_PVCCIN_CPU0_BOOTR8
  BOOT  = SW_PVCCIN_CPU0_BOOT8
  PWM  = PVCCIN_CPU0_PWM8
  EN  = PVCCIN_CPU0_VDD8
  TOUT_FLT  = PVCCIN_CPU0_ATSEN
  LSET  = PVCCIN_CPU0_LSET8
  IOUT  = PVCCIN_CPU0_IMON8
  REFIN  = PVCCIN_CPU0_VREF
  PGND3  = GND
  GL2  = NC

(kicad_pcb
	(version 20260206)
	(generator "pcbnew")
	(generator_version "10.0")
	(general
		(thickness 1.6)
		(legacy_teardrops no)
	)
	(paper "A4")
	(title_block
		(title "03242023_DA0F0TMBIJ0_F0T_Motherboard_J_brd_V01_OCP.brd")
		(comment 1 "Grand Teton / footprints 2904-2904 of 6105")
	)
	(layers
		(0 "F.Cu" signal "TOP")
		(4 "In1.Cu" signal "GND")
		(6 "In2.Cu" signal "IN1")
		(8 "In3.Cu" signal "GND1")
		(10 "In4.Cu" signal "IN2")
		(12 "In5.Cu" signal "GND2")
		(14 "In6.Cu" signal "IN3")
		(16 "In7.Cu" signal "GND3")
		(18 "In8.Cu" signal "VCC")
		(20 "In9.Cu" signal "VCC1")
		(22 "In10.Cu" signal "GND4")
		(24 "In11.Cu" signal "IN4")
		(26 "In12.Cu" signal "GND5")
		(28 "In13.Cu" signal "IN5")
		(30 "In14.Cu" signal "GND6")
		(32 "In15.Cu" signal "IN6")
		(34 "In16.Cu" signal "GND7")
		(2 "B.Cu" signal "BOTTOM")
		(9 "F.Adhes" user "F.Adhesive")
		(11 "B.Adhes" user "B.Adhesive")
		(13 "F.Paste" user "Package Geometry/Pastemask Top")
		(15 "B.Paste" user "Package Geometry/Pastemask Bottom")
		(5 "F.SilkS" user "Ref Des/Silkscreen Top")
		(7 "B.SilkS" user "Ref Des/Silkscreen Bottom")
		(1 "F.Mask" user "Board Geometry/Soldermask Top")
		(3 "B.Mask" user "Board Geometry/Soldermask Bottom")
		(17 "Dwgs.User" user "User.Drawings")
		(19 "Cmts.User" user "User.Comments")
		(21 "Eco1.User" user "User.Eco1")
		(23 "Eco2.User" user "User.Eco2")
		(25 "Edge.Cuts" user "Board Geometry/Outline")
		(27 "Margin" user)
		(31 "F.CrtYd" user "Package Geometry/Place Bound Top")
		(29 "B.CrtYd" user "Package Geometry/Place Bound Bottom")
		(35 "F.Fab" user "Ref Des/Assembly Top")
		(33 "B.Fab" user "Ref Des/Assembly Bottom")
	)
	(footprint ""
		(layer "F.Cu")
		(at 385.740148 -342.917018)
		(property "Reference" "PU6_P0_8"
			(at -3.30454 -6.38683 0)
			(unlocked yes)
			(layer "F.SilkS")
			(effects
				(font
					(size 0.7874 0.5842)
					(thickness 0.1524)
				)
				(justify left)
			)
		)
		(property "Value" ""
			(at 0 0 0)
			(layer "F.Fab")
			(effects
				(font
					(size 1.27 1.27)
				)
			)
		)
		(duplicate_pad_numbers_are_jumpers no)
		(fp_line
			(start -2.500122 -2.999994)
			(end -2.24409 -2.999994)
			(stroke
				(width 0.1524)
				(type default)
			)
			(layer "F.SilkS")
		)
		(fp_line
			(start -2.500122 -2.529078)
			(end -2.500122 -2.999994)
			(stroke
				(width 0.1524)
				(type default)
			)
			(layer "F.SilkS")
		)
		(fp_line
			(start -2.500122 0.6604)
			(end -2.500122 0.229108)
			(stroke
				(width 0.1524)
				(type default)
			)
			(layer "F.SilkS")
		)
		(fp_line
			(start -2.500122 2.999994)
			(end -2.500122 2.339594)
			(stroke
				(width 0.1524)
				(type default)
			)
			(layer "F.SilkS")
		)
		(fp_line
			(start -2.2987 2.999994)
			(end -2.500122 2.999994)
			(stroke
				(width 0.1524)
				(type default)
			)
			(layer "F.SilkS")
		)
		(fp_line
			(start 2.31394 -2.999994)
			(end 2.500122 -2.999994)
			(stroke
				(width 0.1524)
				(type default)
			)
			(layer "F.SilkS")
		)
		(fp_line
			(start 2.500122 -2.999994)
			(end 2.500122 -2.44348)
			(stroke
				(width 0.1524)
				(type default)
			)
			(layer "F.SilkS")
		)
		(fp_line
			(start 2.500122 2.339594)
			(end 2.500122 2.999994)
			(stroke
				(width 0.1524)
				(type default)
			)
			(layer "F.SilkS")
		)
		(fp_line
			(start 2.500122 2.999994)
			(end 2.2987 2.999994)
			(stroke
				(width 0.1524)
				(type default)
			)
			(layer "F.SilkS")
		)
		(fp_poly
			(pts
				(xy -2.21996 -3.632454) (xy -2.72796 -2.616454) (xy -3.23596 -3.632454)
			)
			(stroke
				(width 0)
				(type default)
			)
			(fill yes)
			(layer "F.SilkS")
		)
		(fp_line
			(start -2.500122 -2.999994)
			(end 2.500122 -2.999994)
			(stroke
				(width 0.1)
				(type default)
			)
			(layer "F.Fab")
		)
		(fp_line
			(start -2.500122 2.999994)
			(end -2.500122 -2.999994)
			(stroke
				(width 0.1)
				(type default)
			)
			(layer "F.Fab")
		)
		(fp_line
			(start 2.500122 -2.999994)
			(end 2.500122 2.999994)
			(stroke
				(width 0.1)
				(type default)
			)
			(layer "F.Fab")
		)
		(fp_line
			(start 2.500122 2.999994)
			(end -2.500122 2.999994)
			(stroke
				(width 0.1)
				(type default)
			)
			(layer "F.Fab")
		)
		(fp_poly
			(pts
				(xy -4.218432 -2.783078) (xy -4.218432 -1.767078) (xy -3.202432 -2.275078)
			)
			(stroke
				(width 0)
				(type default)
			)
			(fill yes)
			(layer "F.Fab")
		)
		(pad "1" smd rect
			(at -2.400046 -2.275078 90)
			(size 0.2286 0.6096)
			(layers "F.Cu" "F.Mask" "F.Paste")
			(net "PVCCIN_CPU0_VOS8")
		)
		(pad "2" smd rect
			(at -2.400046 -1.82499 90)
			(size 0.2286 0.6096)
			(layers "F.Cu" "F.Mask" "F.Paste")
			(net "GND")
		)
		(pad "3" smd rect
			(at -2.400046 -1.374902 90)
			(size 0.2286 0.6096)
			(layers "F.Cu" "F.Mask" "F.Paste")
			(net "PVCCIN_CPU0_VDD8")
		)
		(pad "4" smd rect
			(at -2.400046 -0.925068 90)
			(size 0.2286 0.6096)
			(layers "F.Cu" "F.Mask" "F.Paste")
			(net "PVCCIN_CPU0_PVCC")
		)
		(pad "5" smd rect
			(at -2.400046 -0.47498 90)
			(size 0.2286 0.6096)
			(layers "F.Cu" "F.Mask" "F.Paste")
			(net "GND")
		)
		(pad "6" smd rect
			(at -2.400046 -0.024892 90)
			(size 0.2286 0.6096)
			(layers "F.Cu" "F.Mask" "F.Paste")
			(net "Net_8565")
		)
		(pad "7_9-20_24" smd circle
			(at 0 1.150112 90)
			(size 0 0)
			(layers "F.Cu" "F.Mask" "F.Paste")
			(net "GND")
		)
		(pad "10_19" smd rect
			(at 0 2.899918 90)
			(size 0.6096 4.318)
			(layers "F.Cu" "F.Mask" "F.Paste")
			(net "SW_PVCCIN_CPU0_SW8")
		)
		(pad "25_29" smd rect
			(at 1.549908 -1.279906 270)
			(size 2.0574 2.3114)
			(layers "F.Cu" "F.Mask" "F.Paste")
			(net "SW_P12V_PVCCIN_CPU0_FLT")
		)
		(pad "30" smd rect
			(at 2.05994 -2.899918)
			(size 0.2286 0.6096)
			(layers "F.Cu" "F.Mask" "F.Paste")
			(net "SW_P12V_PVCCIN_CPU0_FLT")
		)
		(pad "31" smd rect
			(at 1.610106 -2.899918)
			(size 0.2286 0.6096)
			(layers "F.Cu" "F.Mask" "F.Paste")
			(net "Net_8566")
		)
		(pad "32" smd rect
			(at 1.160018 -2.899918)
			(size 0.2286 0.6096)
			(layers "F.Cu" "F.Mask" "F.Paste")
			(net "SW_PVCCIN_CPU0_BOOTR8")
		)
		(pad "33" smd rect
			(at 0.70993 -2.899918)
			(size 0.2286 0.6096)
			(layers "F.Cu" "F.Mask" "F.Paste")
			(net "SW_PVCCIN_CPU0_BOOT8")
		)
		(pad "34" smd rect
			(at 0.260096 -2.899918)
			(size 0.2286 0.6096)
			(layers "F.Cu" "F.Mask" "F.Paste")
			(net "PVCCIN_CPU0_PWM8")
		)
		(pad "35" smd rect
			(at -0.189992 -2.899918)
			(size 0.2286 0.6096)
			(layers "F.Cu" "F.Mask" "F.Paste")
			(net "PVCCIN_CPU0_VDD8")
		)
		(pad "36" smd rect
			(at -0.64008 -2.899918)
			(size 0.2286 0.6096)
			(layers "F.Cu" "F.Mask" "F.Paste")
			(net "PVCCIN_CPU0_ATSEN")
		)
		(pad "37" smd rect
			(at -1.089914 -2.899918)
			(size 0.2286 0.6096)
			(layers "F.Cu" "F.Mask" "F.Paste")
			(net "PVCCIN_CPU0_LSET8")
		)
		(pad "38" smd rect
			(at -1.540002 -2.899918)
			(size 0.2286 0.6096)
			(layers "F.Cu" "F.Mask" "F.Paste")
			(net "PVCCIN_CPU0_IMON8")
		)
		(pad "39" smd rect
			(at -1.99009 -2.899918)
			(size 0.2286 0.6096)
			(layers "F.Cu" "F.Mask" "F.Paste")
			(net "PVCCIN_CPU0_VREF")
		)
		(pad "40" smd rect
			(at -0.87503 -1.27508)
			(size 1.7526 1.9558)
			(layers "F.Cu" "F.Mask" "F.Paste")
			(net "GND")
		)
		(pad "41" smd rect
			(at -1.525016 0.249936 270)
			(size 0.3048 0.4572)
			(layers "F.Cu" "F.Mask" "F.Paste")
			(net "Net_8564")
		)
		(zone
			(layer "F.Cu")
			(hatch none 0.5)
			(connect_pads
				(clearance 0)
			)
			(min_thickness 0.25)
			(keepout
				(tracks not_allowed)
				(vias allowed)
				(pads allowed)
				(copperpour not_allowed)
				(footprints allowed)
			)
			(placement
				(enabled no)
				(sheetname "")
			)
			(fill
				(thermal_gap 0.5)
				(thermal_bridge_width 0.5)
				(island_removal_mode 0)
			)
			(polygon
				(pts
					(xy 383.240026 -339.917024) (xy 383.240026 -340.666324) (xy 388.24027 -340.666324) (xy 388.24027 -339.917024)
					(xy 387.949948 -339.917024) (xy 387.949948 -340.3727) (xy 383.530348 -340.3727) (xy 383.530348 -339.917024)
				)
			)
		)
		(zone
			(layer "F.Cu")
			(hatch none 0.5)
			(connect_pads
				(clearance 0)
			)
			(min_thickness 0.25)
			(keepout
				(tracks not_allowed)
				(vias allowed)
				(pads allowed)
				(copperpour not_allowed)
				(footprints allowed)
			)
			(placement
				(enabled no)
				(sheetname "")
			)
			(fill
				(thermal_gap 0.5)
				(thermal_bridge_width 0.5)
				(island_removal_mode 0)
			)
			(polygon
				(pts
					(xy 384.494532 -342.844628) (xy 384.72364 -342.844628) (xy 384.789426 -342.778842) (xy 384.789426 -342.167718)
					(xy 383.240026 -342.167718) (xy 383.240026 -342.62441) (xy 383.935732 -342.62441) (xy 383.935732 -342.463882)
					(xy 384.494532 -342.463882)
				)
			)
		)
	)
)
